(kicad_pcb
	(version 20260206)
	(generator "pcbnew")
	(generator_version "10.0")
	(general
		(thickness 1.6)
		(legacy_teardrops no)
	)
	(paper "A4")
	(title_block
		(title "Bryce Canyon_F.DPB_16315-1-OCP.brd")
		(comment 1 "Bryce Canyon / footprints 2010-2016 of 2223")
	)
	(layers
		(0 "F.Cu" signal "TOP")
		(4 "In1.Cu" signal "L2GND")
		(6 "In2.Cu" signal "L3")
		(8 "In3.Cu" signal "L4GND")
		(10 "In4.Cu" signal "L5")
		(12 "In5.Cu" signal "L6VCC")
		(14 "In6.Cu" signal "L7VCC")
		(16 "In7.Cu" signal "L8")
		(18 "In8.Cu" signal "L9GND")
		(20 "In9.Cu" signal "L10")
		(22 "In10.Cu" signal "L11GND")
		(2 "B.Cu" signal "BOTTOM")
		(9 "F.Adhes" user "F.Adhesive")
		(11 "B.Adhes" user "B.Adhesive")
		(13 "F.Paste" user "Package Geometry/Pastemask Top")
		(15 "B.Paste" user "Package Geometry/Pastemask Bottom")
		(5 "F.SilkS" user "Ref Des/Silkscreen Top")
		(7 "B.SilkS" user "Ref Des/Silkscreen Bottom")
		(1 "F.Mask" user "Board Geometry/Soldermask Top")
		(3 "B.Mask" user "Board Geometry/Soldermask Bottom")
		(17 "Dwgs.User" user "User.Drawings")
		(19 "Cmts.User" user "User.Comments")
		(21 "Eco1.User" user "User.Eco1")
		(23 "Eco2.User" user "User.Eco2")
		(25 "Edge.Cuts" user "Board Geometry/Outline")
		(27 "Margin" user)
		(31 "F.CrtYd" user "Package Geometry/Place Bound Top")
		(29 "B.CrtYd" user "Package Geometry/Place Bound Bottom")
		(35 "F.Fab" user "Ref Des/Assembly Top")
		(33 "B.Fab" user "Ref Des/Assembly Bottom")
	)
	(footprint ""
		(layer "F.Cu")
		(at 127.15875 -47.749968 -90)
		(property "Reference" "VIA66"
			(at 0 0 270)
			(layer "F.SilkS")
			(hide yes)
			(effects
				(font
					(size 1.27 1.27)
				)
			)
		)
		(property "Value" "100OHM-8L-1D6MM-L18L16-GP"
			(at -3.7211 -4.5085 270)
			(unlocked yes)
			(layer "F.Fab")
			(hide yes)
			(effects
				(font
					(size 1.016 1.016)
					(thickness 0.1524)
				)
			)
		)
		(property "Device Type" "VIA-PCIE-4P-394076"
			(at -3.7211 -6.0325 270)
			(unlocked yes)
			(layer "F.Fab")
			(hide yes)
			(effects
				(font
					(size 1.016 1.016)
					(thickness 0.1524)
				)
			)
		)
		(duplicate_pad_numbers_are_jumpers no)
		(fp_rect
			(start -1.9685 0.381)
			(end 1.9685 -0.381)
			(stroke
				(width 0)
				(type default)
			)
			(fill no)
			(layer "F.CrtYd")
		)
		(fp_rect
			(start -1.9685 0.381)
			(end 1.9685 -0.381)
			(stroke
				(width 0)
				(type default)
			)
			(fill no)
			(layer "F.Fab")
		)
		(pad "1" thru_hole circle
			(at -1.5875 0 270)
			(size 0.508 0.508)
			(drill 0.254)
			(layers "*.Cu" "*.Mask")
			(remove_unused_layers no)
			(net "GND")
			(clearance 0.127)
			(thermal_gap 0.127)
		)
		(pad "2" thru_hole circle
			(at -0.5715 0 270)
			(size 0.508 0.508)
			(drill 0.254)
			(layers "*.Cu" "*.Mask")
			(remove_unused_layers no)
			(net "PHY_DRV_A_TO_SCC_A_27_DP")
			(clearance 0.127)
			(thermal_gap 0.127)
		)
		(pad "3" thru_hole circle
			(at 0.5715 0 270)
			(size 0.508 0.508)
			(drill 0.254)
			(layers "*.Cu" "*.Mask")
			(remove_unused_layers no)
			(net "PHY_DRV_A_TO_SCC_A_27_DN")
			(clearance 0.127)
			(thermal_gap 0.127)
		)
		(pad "4" thru_hole circle
			(at 1.5875 0 270)
			(size 0.508 0.508)
			(drill 0.254)
			(layers "*.Cu" "*.Mask")
			(remove_unused_layers no)
			(net "GND")
			(clearance 0.127)
			(thermal_gap 0.127)
		)
	)
	(footprint ""
		(layer "F.Cu")
		(at 412.477458 -284.022546)
		(property "Reference" "Q296"
			(at 0 0 0)
			(layer "F.SilkS")
			(hide yes)
			(effects
				(font
					(size 1.27 1.27)
				)
			)
		)
		(property "Value" "SSM3K324R-GP"
			(at 0.127 -8.9662 0)
			(unlocked yes)
			(layer "F.Fab")
			(hide yes)
			(effects
				(font
					(size 1.016 1.016)
					(thickness 0.1524)
				)
			)
		)
		(property "Device Type" "SOT23DGS2D4H35"
			(at 0.127 -10.4902 0)
			(unlocked yes)
			(layer "F.Fab")
			(hide yes)
			(effects
				(font
					(size 1.016 1.016)
					(thickness 0.1524)
				)
			)
		)
		(duplicate_pad_numbers_are_jumpers no)
		(fp_line
			(start -1.651 -1.778)
			(end -1.651 1.778)
			(stroke
				(width 0.1524)
				(type default)
			)
			(layer "F.SilkS")
		)
		(fp_line
			(start -1.651 1.778)
			(end 1.651 1.778)
			(stroke
				(width 0.1524)
				(type default)
			)
			(layer "F.SilkS")
		)
		(fp_line
			(start 1.651 -1.778)
			(end -1.651 -1.778)
			(stroke
				(width 0.1524)
				(type default)
			)
			(layer "F.SilkS")
		)
		(fp_line
			(start 1.651 1.778)
			(end 1.651 -1.778)
			(stroke
				(width 0.1524)
				(type default)
			)
			(layer "F.SilkS")
		)
		(fp_poly
			(pts
				(xy -1.778 1.8796) (xy -1.778 -1.8796) (xy 1.778 -1.8796) (xy 1.778 1.8796)
			)
			(stroke
				(width 0)
				(type default)
			)
			(fill no)
			(layer "F.CrtYd")
		)
		(fp_poly
			(pts
				(xy -1.778 1.8796) (xy -1.778 -1.8796) (xy 1.778 -1.8796) (xy 1.778 1.8796)
			)
			(stroke
				(width 0)
				(type default)
			)
			(fill no)
			(layer "F.Fab")
		)
		(pad "D" smd custom
			(at 0 -0.9525)
			(size 0.1905 0.1905)
			(layers "F.Cu" "F.Mask" "F.Paste")
			(net "DRV_ACT_33_N")
			(options
				(clearance outline)
				(anchor circle)
			)
			(primitives
				(gr_poly
					(pts
						(arc
							(start -0.1778 0.5715)
							(mid -0.321484 0.511984)
							(end -0.381 0.3683)
						)
						(arc
							(start -0.381 -0.3683)
							(mid -0.321484 -0.511984)
							(end -0.1778 -0.5715)
						)
						(arc
							(start 0.1778 -0.5715)
							(mid 0.321484 -0.511984)
							(end 0.381 -0.3683)
						)
						(arc
							(start 0.381 0.3683)
							(mid 0.321484 0.511984)
							(end 0.1778 0.5715)
						)
					)
					(width 0)
					(fill yes)
				)
			)
		)
		(pad "G" smd custom
			(at -0.98425 0.9525)
			(size 0.1905 0.1905)
			(layers "F.Cu" "F.Mask" "F.Paste")
			(net "DRIVE_B_33_ACT")
			(options
				(clearance outline)
				(anchor circle)
			)
			(primitives
				(gr_poly
					(pts
						(arc
							(start -0.1778 0.5715)
							(mid -0.321484 0.511984)
							(end -0.381 0.3683)
						)
						(arc
							(start -0.381 -0.3683)
							(mid -0.321484 -0.511984)
							(end -0.1778 -0.5715)
						)
						(arc
							(start 0.1778 -0.5715)
							(mid 0.321484 -0.511984)
							(end 0.381 -0.3683)
						)
						(arc
							(start 0.381 0.3683)
							(mid 0.321484 0.511984)
							(end 0.1778 0.5715)
						)
					)
					(width 0)
					(fill yes)
				)
			)
		)
		(pad "S" smd custom
			(at 0.98425 0.9525)
			(size 0.1905 0.1905)
			(layers "F.Cu" "F.Mask" "F.Paste")
			(net "GND")
			(options
				(clearance outline)
				(anchor circle)
			)
			(primitives
				(gr_poly
					(pts
						(arc
							(start -0.1778 0.5715)
							(mid -0.321484 0.511984)
							(end -0.381 0.3683)
						)
						(arc
							(start -0.381 -0.3683)
							(mid -0.321484 -0.511984)
							(end -0.1778 -0.5715)
						)
						(arc
							(start 0.1778 -0.5715)
							(mid 0.321484 -0.511984)
							(end 0.381 -0.3683)
						)
						(arc
							(start 0.381 0.3683)
							(mid 0.321484 0.511984)
							(end 0.1778 0.5715)
						)
					)
					(width 0)
					(fill yes)
				)
			)
		)
	)
	(footprint ""
		(layer "F.Cu")
		(at 143.074898 -46.649894 180)
		(property "Reference" "D28"
			(at 0 0 180)
			(layer "F.SilkS")
			(hide yes)
			(effects
				(font
					(size 1.27 1.27)
				)
			)
		)
		(property "Value" "RB551V30-GP"
			(at 0 -6.7818 180)
			(unlocked yes)
			(layer "F.Fab")
			(hide yes)
			(effects
				(font
					(size 1.016 1.016)
					(thickness 0.1524)
				)
			)
		)
		(property "Device Type" "SOD323AKH38"
			(at 0 -8.6868 180)
			(unlocked yes)
			(layer "F.Fab")
			(hide yes)
			(effects
				(font
					(size 1.016 1.016)
					(thickness 0.1524)
				)
			)
		)
		(duplicate_pad_numbers_are_jumpers no)
		(fp_line
			(start 0.889 2.159)
			(end -0.889 2.159)
			(stroke
				(width 0.1524)
				(type default)
			)
			(layer "F.SilkS")
		)
		(fp_line
			(start 0.889 -1.9304)
			(end 0.889 2.159)
			(stroke
				(width 0.1524)
				(type default)
			)
			(layer "F.SilkS")
		)
		(fp_line
			(start 0.762 2.0574)
			(end -0.762 2.0574)
			(stroke
				(width 0.508)
				(type default)
			)
			(layer "F.SilkS")
		)
		(fp_line
			(start -0.889 2.159)
			(end -0.889 -1.9304)
			(stroke
				(width 0.1524)
				(type default)
			)
			(layer "F.SilkS")
		)
		(fp_line
			(start -0.889 -1.9304)
			(end 0.889 -1.9304)
			(stroke
				(width 0.1524)
				(type default)
			)
			(layer "F.SilkS")
		)
		(fp_rect
			(start -1.016 2.3114)
			(end 1.016 -2.0066)
			(stroke
				(width 0)
				(type default)
			)
			(fill no)
			(layer "F.CrtYd")
		)
		(fp_poly
			(pts
				(xy -1.016 -2.0066) (xy 1.016 -2.0066) (xy 1.016 2.3114) (xy -1.016 2.3114)
			)
			(stroke
				(width 0)
				(type default)
			)
			(fill no)
			(layer "F.Fab")
		)
		(pad "A" smd rect
			(at 0 -1.143 180)
			(size 0.5588 1.016)
			(layers "F.Cu" "F.Mask" "F.Paste")
			(net "SW_HDD_R28")
		)
		(pad "K" smd rect
			(at 0 1.143 180)
			(size 0.5588 1.016)
			(layers "F.Cu" "F.Mask" "F.Paste")
			(net "SW_HDD_N28")
		)
	)
	(footprint ""
		(layer "F.Cu")
		(at 149.196298 -274.871942 -90)
		(property "Reference" "R234"
			(at 0 0 270)
			(layer "F.SilkS")
			(hide yes)
			(effects
				(font
					(size 1.27 1.27)
				)
			)
		)
		(property "Value" "0R2J-2-GP"
			(at 0.064008 -3.993896 270)
			(unlocked yes)
			(layer "F.Fab")
			(hide yes)
			(effects
				(font
					(size 1.016 1.016)
					(thickness 0.1524)
				)
			)
		)
		(property "Device Type" "R402H16"
			(at 0.064008 -5.517896 270)
			(unlocked yes)
			(layer "F.Fab")
			(hide yes)
			(effects
				(font
					(size 1.016 1.016)
					(thickness 0.1524)
				)
			)
		)
		(duplicate_pad_numbers_are_jumpers no)
		(fp_line
			(start -0.508 -0.9398)
			(end -0.508 0.9398)
			(stroke
				(width 0.1524)
				(type default)
			)
			(layer "F.SilkS")
		)
		(fp_line
			(start 0.508 -0.9398)
			(end -0.508 -0.9398)
			(stroke
				(width 0.1524)
				(type default)
			)
			(layer "F.SilkS")
		)
		(fp_rect
			(start -0.508 0.9398)
			(end 0.508 -0.9398)
			(stroke
				(width 0)
				(type default)
			)
			(fill no)
			(layer "F.CrtYd")
		)
		(fp_rect
			(start -0.508 0.9398)
			(end 0.508 -0.9398)
			(stroke
				(width 0)
				(type default)
			)
			(fill no)
			(layer "F.Fab")
		)
		(pad "1" smd custom
			(at 0 -0.4445 270)
			(size 0.1397 0.1397)
			(layers "F.Cu" "F.Mask" "F.Paste")
			(net "DRIVE_A_4_PWR")
			(options
				(clearance outline)
				(anchor circle)
			)
			(primitives
				(gr_poly
					(pts
						(arc
							(start -0.1778 -0.2794)
							(mid -0.249642 -0.249642)
							(end -0.2794 -0.1778)
						)
						(arc
							(start -0.2794 0.1778)
							(mid -0.249642 0.249642)
							(end -0.1778 0.2794)
						)
						(arc
							(start 0.1778 0.2794)
							(mid 0.249642 0.249642)
							(end 0.2794 0.1778)
						)
						(arc
							(start 0.2794 -0.1778)
							(mid 0.249642 -0.249642)
							(end 0.1778 -0.2794)
						)
					)
					(width 0)
					(fill yes)
				)
			)
		)
		(pad "2" smd custom
			(at 0 0.4445 270)
			(size 0.1397 0.1397)
			(layers "F.Cu" "F.Mask" "F.Paste")
			(net "SW_PWR_R_HDD4")
			(options
				(clearance outline)
				(anchor circle)
			)
			(primitives
				(gr_poly
					(pts
						(arc
							(start -0.1778 -0.2794)
							(mid -0.249642 -0.249642)
							(end -0.2794 -0.1778)
						)
						(arc
							(start -0.2794 0.1778)
							(mid -0.249642 0.249642)
							(end -0.1778 0.2794)
						)
						(arc
							(start 0.1778 0.2794)
							(mid 0.249642 0.249642)
							(end 0.2794 0.1778)
						)
						(arc
							(start 0.2794 -0.1778)
							(mid 0.249642 -0.249642)
							(end 0.1778 -0.2794)
						)
					)
					(width 0)
					(fill yes)
				)
			)
		)
	)
	(footprint ""
		(layer "F.Cu")
		(at 344.026998 -21.142452)
		(property "Reference" "R455"
			(at 0 0 0)
			(layer "F.SilkS")
			(hide yes)
			(effects
				(font
					(size 1.27 1.27)
				)
			)
		)
		(property "Value" "4K7R2F-GP"
			(at 0.064008 -3.993896 0)
			(unlocked yes)
			(layer "F.Fab")
			(hide yes)
			(effects
				(font
					(size 1.016 1.016)
					(thickness 0.1524)
				)
			)
		)
		(property "Device Type" "R402H16"
			(at 0.064008 -5.517896 0)
			(unlocked yes)
			(layer "F.Fab")
			(hide yes)
			(effects
				(font
					(size 1.016 1.016)
					(thickness 0.1524)
				)
			)
		)
		(duplicate_pad_numbers_are_jumpers no)
		(fp_line
			(start -0.508 -0.9398)
			(end -0.508 0.9398)
			(stroke
				(width 0.1524)
				(type default)
			)
			(layer "F.SilkS")
		)
		(fp_line
			(start 0.508 -0.9398)
			(end -0.508 -0.9398)
			(stroke
				(width 0.1524)
				(type default)
			)
			(layer "F.SilkS")
		)
		(fp_rect
			(start -0.508 0.9398)
			(end 0.508 -0.9398)
			(stroke
				(width 0)
				(type default)
			)
			(fill no)
			(layer "F.CrtYd")
		)
		(fp_rect
			(start -0.508 0.9398)
			(end 0.508 -0.9398)
			(stroke
				(width 0)
				(type default)
			)
			(fill no)
			(layer "F.Fab")
		)
		(pad "1" smd custom
			(at 0 -0.4445)
			(size 0.1397 0.1397)
			(layers "F.Cu" "F.Mask" "F.Paste")
			(net "GND")
			(options
				(clearance outline)
				(anchor circle)
			)
			(primitives
				(gr_poly
					(pts
						(arc
							(start -0.1778 -0.2794)
							(mid -0.249642 -0.249642)
							(end -0.2794 -0.1778)
						)
						(arc
							(start -0.2794 0.1778)
							(mid -0.249642 0.249642)
							(end -0.1778 0.2794)
						)
						(arc
							(start 0.1778 0.2794)
							(mid 0.249642 0.249642)
							(end 0.2794 0.1778)
						)
						(arc
							(start 0.2794 -0.1778)
							(mid 0.249642 -0.249642)
							(end 0.1778 -0.2794)
						)
					)
					(width 0)
					(fill yes)
				)
			)
		)
		(pad "2" smd custom
			(at 0 0.4445)
			(size 0.1397 0.1397)
			(layers "F.Cu" "F.Mask" "F.Paste")
			(net "COMP_B_FAST_THROTTLE_N")
			(options
				(clearance outline)
				(anchor circle)
			)
			(primitives
				(gr_poly
					(pts
						(arc
							(start -0.1778 -0.2794)
							(mid -0.249642 -0.249642)
							(end -0.2794 -0.1778)
						)
						(arc
							(start -0.2794 0.1778)
							(mid -0.249642 0.249642)
							(end -0.1778 0.2794)
						)
						(arc
							(start 0.1778 0.2794)
							(mid 0.249642 0.249642)
							(end 0.2794 0.1778)
						)
						(arc
							(start 0.2794 -0.1778)
							(mid 0.249642 -0.249642)
							(end 0.1778 -0.2794)
						)
					)
					(width 0)
					(fill yes)
				)
			)
		)
	)
	(footprint ""
		(layer "F.Cu")
		(at 79.924148 -168.126918 -90)
		(property "Reference" "C230"
			(at 0 0 270)
			(layer "F.SilkS")
			(hide yes)
			(effects
				(font
					(size 1.27 1.27)
				)
			)
		)
		(property "Value" "SCD033U25V2KX-GP"
			(at 1.1811 -2.7051 270)
			(unlocked yes)
			(layer "F.Fab")
			(hide yes)
			(effects
				(font
					(size 1.016 1.016)
					(thickness 0.1524)
				)
			)
		)
		(property "Device Type" "C402H22"
			(at 1.1811 -4.2291 270)
			(unlocked yes)
			(layer "F.Fab")
			(hide yes)
			(effects
				(font
					(size 1.016 1.016)
					(thickness 0.1524)
				)
			)
		)
		(duplicate_pad_numbers_are_jumpers no)
		(fp_rect
			(start -0.4318 0.9525)
			(end 0.4318 -0.9525)
			(stroke
				(width 0)
				(type default)
			)
			(fill no)
			(layer "F.CrtYd")
		)
		(fp_rect
			(start -0.4318 0.9525)
			(end 0.4318 -0.9525)
			(stroke
				(width 0)
				(type default)
			)
			(fill no)
			(layer "F.Fab")
		)
		(pad "1" smd custom
			(at 0 -0.4445 270)
			(size 0.1524 0.1524)
			(layers "F.Cu" "F.Mask" "F.Paste")
			(net "SW_HDD_P14")
			(options
				(clearance outline)
				(anchor circle)
			)
			(primitives
				(gr_poly
					(pts
						(arc
							(start 0.3048 -0.2032)
							(mid 0.275042 -0.275042)
							(end 0.2032 -0.3048)
						)
						(arc
							(start -0.2032 -0.3048)
							(mid -0.275042 -0.275042)
							(end -0.3048 -0.2032)
						)
						(arc
							(start -0.3048 0.2032)
							(mid -0.275042 0.275042)
							(end -0.2032 0.3048)
						)
						(arc
							(start 0.2032 0.3048)
							(mid 0.275042 0.275042)
							(end 0.3048 0.2032)
						)
					)
					(width 0)
					(fill yes)
				)
			)
		)
		(pad "2" smd custom
			(at 0 0.4445 270)
			(size 0.1524 0.1524)
			(layers "F.Cu" "F.Mask" "F.Paste")
			(net "GND")
			(options
				(clearance outline)
				(anchor circle)
			)
			(primitives
				(gr_poly
					(pts
						(arc
							(start 0.3048 -0.2032)
							(mid 0.275042 -0.275042)
							(end 0.2032 -0.3048)
						)
						(arc
							(start -0.2032 -0.3048)
							(mid -0.275042 -0.275042)
							(end -0.3048 -0.2032)
						)
						(arc
							(start -0.3048 0.2032)
							(mid -0.275042 0.275042)
							(end -0.2032 0.3048)
						)
						(arc
							(start 0.2032 0.3048)
							(mid 0.275042 0.275042)
							(end 0.3048 0.2032)
						)
					)
					(width 0)
					(fill yes)
				)
			)
		)
	)
	(footprint ""
		(layer "F.Cu")
		(at 409.800044 -209.399886)
		(property "Reference" "FLED10"
			(at 0 0 0)
			(layer "F.SilkS")
			(hide yes)
			(effects
				(font
					(size 1.27 1.27)
				)
			)
		)
		(property "Value" "LED-BY-19-GP"
			(at -2.132076 1.414018 0)
			(unlocked yes)
			(layer "F.Fab")
			(hide yes)
			(effects
				(font
					(size 1.016 1.016)
					(thickness 0.1524)
				)
			)
		)
		(property "Device Type" "LED-1615-4PH26"
			(at -2.132076 -0.109982 0)
			(unlocked yes)
			(layer "F.Fab")
			(hide yes)
			(effects
				(font
					(size 1.016 1.016)
					(thickness 0.1524)
				)
			)
		)
		(duplicate_pad_numbers_are_jumpers no)
		(fp_line
			(start -1.2954 0.254)
			(end -1.2954 1.6002)
			(stroke
				(width 0.508)
				(type default)
			)
			(layer "F.SilkS")
		)
		(fp_line
			(start -1.2954 1.6002)
			(end 1.2954 1.6002)
			(stroke
				(width 0.508)
				(type default)
			)
			(layer "F.SilkS")
		)
		(fp_line
			(start -1.1176 -1.4224)
			(end 1.1176 -1.4224)
			(stroke
				(width 0.1524)
				(type default)
			)
			(layer "F.SilkS")
		)
		(fp_line
			(start -1.1176 1.4224)
			(end -1.1176 -1.4224)
			(stroke
				(width 0.1524)
				(type default)
			)
			(layer "F.SilkS")
		)
		(fp_line
			(start 1.1176 -1.4224)
			(end 1.1176 1.4224)
			(stroke
				(width 0.1524)
				(type default)
			)
			(layer "F.SilkS")
		)
		(fp_line
			(start 1.1176 1.4224)
			(end -1.1176 1.4224)
			(stroke
				(width 0.1524)
				(type default)
			)
			(layer "F.SilkS")
		)
		(fp_line
			(start 1.2954 1.6002)
			(end 1.2954 0.254)
			(stroke
				(width 0.508)
				(type default)
			)
			(layer "F.SilkS")
		)
		(fp_rect
			(start -0.7493 0.8001)
			(end 0.7493 -0.8001)
			(stroke
				(width 0)
				(type default)
			)
			(fill no)
			(layer "F.CrtYd")
		)
		(fp_poly
			(pts
				(xy -1.3716 1.6764) (xy -1.3716 -1.6764) (xy 1.3716 -1.6764) (xy 1.3716 0.0635) (xy 0.7493 0.0635)
				(xy 0.7493 -0.8001) (xy -0.7493 -0.8001) (xy -0.7493 0.8001) (xy 0.7493 0.8001) (xy 0.7493 0.0762)
				(xy 1.3716 0.0762) (xy 1.3716 1.6764)
			)
			(stroke
				(width 0)
				(type default)
			)
			(fill no)
			(layer "F.CrtYd")
		)
		(fp_rect
			(start -1.3716 1.6764)
			(end 1.3716 -1.6764)
			(stroke
				(width 0)
				(type default)
			)
			(fill no)
			(layer "F.Fab")
		)
		(pad "1" smd rect
			(at 0.50038 -0.73025)
			(size 0.7112 0.8636)
			(layers "F.Cu" "F.Mask" "F.Paste")
			(net "DRV_ACT_9")
		)
		(pad "2" smd rect
			(at -0.50038 -0.73025)
			(size 0.7112 0.8636)
			(layers "F.Cu" "F.Mask" "F.Paste")
			(net "FLT_HDD9")
		)
		(pad "3" smd rect
			(at 0.50038 0.73025)
			(size 0.7112 0.8636)
			(layers "F.Cu" "F.Mask" "F.Paste")
			(net "DRV_ACT_9_N")
		)
		(pad "4" smd rect
			(at -0.50038 0.73025)
			(size 0.7112 0.8636)
			(layers "F.Cu" "F.Mask" "F.Paste")
			(net "FLT_HDD9_N")
		)
	)
)
